M48
;DRILL file {KiCad (5.0.1)-3} date 10/04/2019 15:36:23
;FORMAT={-:-/ absolute / metric / decimal}
FMAT,2
METRIC,TZ
T1C3.030
%
G90
G05
M71
T1
X30.101Y83.698
X5.901Y83.698
X5.901Y61.698
X30.101Y53.498
X30.101Y35.698
X5.901Y24.666
X5.901Y6.866
X30.101Y24.666
X30.101Y6.866
X5.901Y53.498
X5.901Y35.698
X30.101Y61.698
T0
M30
